(kicad_pcb
	(version 20260206)
	(generator "pcbnew")
	(generator_version "10.0")
	(general
		(thickness 1.6)
		(legacy_teardrops no)
	)
	(paper "A4")
	(title_block
		(title "v2-pdb — ms_pdb_v2.brd")
		(comment 1 "Open CloudServer (Microsoft) / footprints 315-318 of 348")
	)
	(layers
		(0 "F.Cu" signal "TOP")
		(4 "In1.Cu" signal "GND")
		(6 "In2.Cu" signal "IN1")
		(8 "In3.Cu" signal "VCC")
		(10 "In4.Cu" signal "VCC1")
		(12 "In5.Cu" signal "IN2")
		(14 "In6.Cu" signal "GND1")
		(2 "B.Cu" signal "BOTTOM")
		(9 "F.Adhes" user "F.Adhesive")
		(11 "B.Adhes" user "B.Adhesive")
		(13 "F.Paste" user "Package Geometry/Pastemask Top")
		(15 "B.Paste" user "Package Geometry/Pastemask Bottom")
		(5 "F.SilkS" user "Ref Des/Silkscreen Top")
		(7 "B.SilkS" user "Ref Des/Silkscreen Bottom")
		(1 "F.Mask" user "Board Geometry/Soldermask Top")
		(3 "B.Mask" user "Board Geometry/Soldermask Bottom")
		(17 "Dwgs.User" user "User.Drawings")
		(19 "Cmts.User" user "User.Comments")
		(21 "Eco1.User" user "User.Eco1")
		(23 "Eco2.User" user "User.Eco2")
		(25 "Edge.Cuts" user "Board Geometry/Outline")
		(27 "Margin" user)
		(31 "F.CrtYd" user "Package Geometry/Place Bound Top")
		(29 "B.CrtYd" user "Package Geometry/Place Bound Bottom")
		(35 "F.Fab" user "Ref Des/Assembly Top")
		(33 "B.Fab" user "Ref Des/Assembly Bottom")
	)
	(footprint ""
		(layer "F.Cu")
		(at 14.034516 -140.843 -90)
		(property "Reference" "J29"
			(at -5.54101 6.072378 0)
			(unlocked yes)
			(layer "F.SilkS")
			(effects
				(font
					(size 0.7874 0.5842)
					(thickness 0.1524)
				)
				(justify left)
			)
		)
		(property "Value" ""
			(at 0 0 270)
			(layer "F.Fab")
			(effects
				(font
					(size 1.27 1.27)
				)
			)
		)
		(duplicate_pad_numbers_are_jumpers no)
		(fp_line
			(start -3.754882 12.899898)
			(end -3.754882 3.7846)
			(stroke
				(width 0.1524)
				(type default)
			)
			(layer "F.SilkS")
		)
		(fp_line
			(start 12.644882 12.899898)
			(end -3.754882 12.899898)
			(stroke
				(width 0.1524)
				(type default)
			)
			(layer "F.SilkS")
		)
		(fp_line
			(start 12.644882 3.7846)
			(end 12.644882 12.899898)
			(stroke
				(width 0.1524)
				(type default)
			)
			(layer "F.SilkS")
		)
		(fp_line
			(start -3.754882 1.2192)
			(end -3.754882 -3.800094)
			(stroke
				(width 0.1524)
				(type default)
			)
			(layer "F.SilkS")
		)
		(fp_line
			(start -3.754882 -3.800094)
			(end 12.644882 -3.800094)
			(stroke
				(width 0.1524)
				(type default)
			)
			(layer "F.SilkS")
		)
		(fp_line
			(start 12.644882 -3.800094)
			(end 12.644882 1.2192)
			(stroke
				(width 0.1524)
				(type default)
			)
			(layer "F.SilkS")
		)
		(fp_poly
			(pts
				(xy -4.125214 0) (xy -5.806186 0.840486) (xy -5.806186 -0.840486)
			)
			(stroke
				(width 0)
				(type default)
			)
			(fill yes)
			(layer "F.SilkS")
		)
		(fp_poly
			(pts
				(xy -2.591562 11.176) (xy 1.370838 11.176) (xy 1.370838 9.7282) (xy -2.591562 9.7282)
			)
			(stroke
				(width 0)
				(type default)
			)
			(fill no)
			(layer "B.CrtYd")
		)
		(fp_poly
			(pts
				(xy 7.5184 11.176) (xy 11.4808 11.176) (xy 11.4808 9.7282) (xy 7.5184 9.7282)
			)
			(stroke
				(width 0)
				(type default)
			)
			(fill no)
			(layer "B.CrtYd")
		)
		(fp_poly
			(pts
				(xy 9.627362 -3.256026) (xy 9.627362 -1.808226) (xy 8.357362 -1.808226) (xy 8.357362 0.731774) (xy -0.735838 0.731774)
				(xy -0.735838 -0.741426) (xy 0.534162 -0.741426) (xy 0.534162 -3.256026)
			)
			(stroke
				(width 0)
				(type default)
			)
			(fill no)
			(layer "B.CrtYd")
		)
		(fp_poly
			(pts
				(arc
					(start 12.320016 1.268222)
					(mid 12.320016 3.732022)
					(end 12.320016 1.268222)
				)
			)
			(stroke
				(width 0)
				(type default)
			)
			(fill no)
			(layer "B.CrtYd")
		)
		(fp_poly
			(pts
				(arc
					(start -3.430016 1.267968)
					(mid -3.430016 3.732276)
					(end -3.430016 1.267968)
				)
			)
			(stroke
				(width 0)
				(type default)
			)
			(fill no)
			(layer "B.CrtYd")
		)
		(fp_poly
			(pts
				(arc
					(start -1.27 4.4958)
					(mid -1.27 8.2042)
					(end -1.27 4.4958)
				)
			)
			(stroke
				(width 0)
				(type default)
			)
			(fill no)
			(layer "B.CrtYd")
		)
		(fp_poly
			(pts
				(arc
					(start 10.16 4.4958)
					(mid 10.16 8.2042)
					(end 10.16 4.4958)
				)
			)
			(stroke
				(width 0)
				(type default)
			)
			(fill no)
			(layer "B.CrtYd")
		)
		(fp_poly
			(pts
				(xy -3.754882 12.899898)
				(arc
					(start -3.754882 3.688334)
					(mid -4.662083 2.499901)
					(end -3.754882 1.311656)
				)
				(xy -3.754882 -3.800094) (xy 12.644882 -3.800094)
				(arc
					(start 12.644882 1.311656)
					(mid 13.551838 2.499901)
					(end 12.644882 3.688334)
				)
				(xy 12.644882 12.899898)
			)
			(stroke
				(width 0)
				(type default)
			)
			(fill no)
			(layer "F.CrtYd")
		)
		(fp_line
			(start -3.754882 12.899898)
			(end -3.754882 -3.800094)
			(stroke
				(width 0.1)
				(type default)
			)
			(layer "F.Fab")
		)
		(fp_line
			(start 12.644882 12.899898)
			(end -3.754882 12.899898)
			(stroke
				(width 0.1)
				(type default)
			)
			(layer "F.Fab")
		)
		(fp_line
			(start -3.754882 -3.800094)
			(end 12.644882 -3.800094)
			(stroke
				(width 0.1)
				(type default)
			)
			(layer "F.Fab")
		)
		(fp_line
			(start 12.644882 -3.800094)
			(end 12.644882 12.899898)
			(stroke
				(width 0.1)
				(type default)
			)
			(layer "F.Fab")
		)
		(fp_poly
			(pts
				(xy -4.125214 0) (xy -5.806186 0.840486) (xy -5.806186 -0.840486)
			)
			(stroke
				(width 0)
				(type default)
			)
			(fill yes)
			(layer "F.Fab")
		)
		(fp_text user "7"
			(at 13.536168 0.140208 0)
			(unlocked yes)
			(layer "F.SilkS")
			(effects
				(font
					(size 0.7874 0.5842)
					(thickness 0.1524)
				)
			)
		)
		(fp_text user "1"
			(at -4.496054 -0.829564 0)
			(unlocked yes)
			(layer "F.SilkS")
			(effects
				(font
					(size 0.7874 0.5842)
					(thickness 0.1524)
				)
			)
		)
		(fp_text user "8"
			(at 13.458952 -2.92354 0)
			(unlocked yes)
			(layer "F.SilkS")
			(effects
				(font
					(size 0.7874 0.5842)
					(thickness 0.1524)
				)
			)
		)
		(fp_text user "2"
			(at -4.559808 -3.01117 0)
			(unlocked yes)
			(layer "F.SilkS")
			(effects
				(font
					(size 0.7874 0.5842)
					(thickness 0.1524)
				)
			)
		)
		(fp_text user "7"
			(at 9.144762 0.002794 0)
			(unlocked yes)
			(layer "B.SilkS")
			(effects
				(font
					(size 0.7874 0.5842)
					(thickness 0.1524)
				)
				(justify mirror)
			)
		)
		(fp_text user "1"
			(at -1.343152 -0.034544 0)
			(unlocked yes)
			(layer "B.SilkS")
			(effects
				(font
					(size 0.7874 0.5842)
					(thickness 0.1524)
				)
				(justify mirror)
			)
		)
		(fp_text user "8"
			(at 10.402062 -2.562606 0)
			(unlocked yes)
			(layer "B.SilkS")
			(effects
				(font
					(size 0.7874 0.5842)
					(thickness 0.1524)
				)
				(justify mirror)
			)
		)
		(fp_text user "2"
			(at -0.225552 -2.612644 0)
			(unlocked yes)
			(layer "B.SilkS")
			(effects
				(font
					(size 0.7874 0.5842)
					(thickness 0.1524)
				)
				(justify mirror)
			)
		)
		(fp_text user "7"
			(at 8.8646 0.085852 270)
			(unlocked yes)
			(layer "B.Fab")
			(effects
				(font
					(size 0.7874 0.5842)
					(thickness 0.000001)
				)
				(justify mirror)
			)
		)
		(fp_text user "1"
			(at -1.1811 -0.053848 270)
			(unlocked yes)
			(layer "B.Fab")
			(effects
				(font
					(size 0.7874 0.5842)
					(thickness 0.000001)
				)
				(justify mirror)
			)
		)
		(fp_text user "8"
			(at 10.1219 -2.479548 270)
			(unlocked yes)
			(layer "B.Fab")
			(effects
				(font
					(size 0.7874 0.5842)
					(thickness 0.000001)
				)
				(justify mirror)
			)
		)
		(fp_text user "2"
			(at -0.0635 -2.631948 270)
			(unlocked yes)
			(layer "B.Fab")
			(effects
				(font
					(size 0.7874 0.5842)
					(thickness 0.000001)
				)
				(justify mirror)
			)
		)
		(fp_text user "7"
			(at 13.2334 -0.079248 270)
			(unlocked yes)
			(layer "F.Fab")
			(effects
				(font
					(size 0.7874 0.5842)
					(thickness 0.000001)
				)
			)
		)
		(fp_text user "1"
			(at -4.4323 -1.019048 270)
			(unlocked yes)
			(layer "F.Fab")
			(effects
				(font
					(size 0.7874 0.5842)
					(thickness 0.000001)
				)
			)
		)
		(fp_text user "2"
			(at -4.4704 -2.581148 270)
			(unlocked yes)
			(layer "F.Fab")
			(effects
				(font
					(size 0.7874 0.5842)
					(thickness 0.000001)
				)
			)
		)
		(fp_text user "8"
			(at 13.2715 -2.593848 270)
			(unlocked yes)
			(layer "F.Fab")
			(effects
				(font
					(size 0.7874 0.5842)
					(thickness 0.000001)
				)
			)
		)
		(pad "" np_thru_hole circle
			(at -1.27 6.35 270)
			(size 3.2004 3.2004)
			(drill 3.2004)
			(layers "*.Cu" "*.Mask")
			(clearance 0.381)
			(thermal_gap 0.381)
		)
		(pad "" np_thru_hole circle
			(at 10.16 6.35 270)
			(size 3.2004 3.2004)
			(drill 3.2004)
			(layers "*.Cu" "*.Mask")
			(clearance 0.381)
			(thermal_gap 0.381)
		)
		(pad "1" thru_hole rect
			(at 0 0 270)
			(size 1.3208 1.3208)
			(drill 0.9144)
			(layers "*.Cu" "*.Mask")
			(remove_unused_layers no)
			(net "LAN1_P1_P")
			(clearance 0.0508)
			(thermal_gap 0.0508)
			(padstack
				(mode front_inner_back)
				(layer "Inner"
					(shape circle)
					(size 1.3208 1.3208)
					(clearance 0.0508)
				)
				(layer "B.Cu"
					(shape rect)
					(size 1.3208 1.3208)
					(clearance 0.0508)
				)
			)
		)
		(pad "2" thru_hole circle
			(at 1.27 -2.54 270)
			(size 1.3208 1.3208)
			(drill 0.9144)
			(layers "*.Cu" "*.Mask")
			(remove_unused_layers no)
			(net "LAN1_P1_N")
			(clearance 0.0508)
			(thermal_gap 0.0508)
		)
		(pad "3" thru_hole circle
			(at 2.54 0 270)
			(size 1.3208 1.3208)
			(drill 0.9144)
			(layers "*.Cu" "*.Mask")
			(remove_unused_layers no)
			(net "LAN1_P2_P")
			(clearance 0.0508)
			(thermal_gap 0.0508)
		)
		(pad "4" thru_hole circle
			(at 3.81 -2.54 270)
			(size 1.3208 1.3208)
			(drill 0.9144)
			(layers "*.Cu" "*.Mask")
			(remove_unused_layers no)
			(net "LAN1_P3_P")
			(clearance 0.0508)
			(thermal_gap 0.0508)
		)
		(pad "5" thru_hole circle
			(at 5.08 0 270)
			(size 1.3208 1.3208)
			(drill 0.9144)
			(layers "*.Cu" "*.Mask")
			(remove_unused_layers no)
			(net "LAN1_P3_N")
			(clearance 0.0508)
			(thermal_gap 0.0508)
		)
		(pad "6" thru_hole circle
			(at 6.35 -2.54 270)
			(size 1.3208 1.3208)
			(drill 0.9144)
			(layers "*.Cu" "*.Mask")
			(remove_unused_layers no)
			(net "LAN1_P2_N")
			(clearance 0.0508)
			(thermal_gap 0.0508)
		)
		(pad "7" thru_hole circle
			(at 7.62 0 270)
			(size 1.3208 1.3208)
			(drill 0.9144)
			(layers "*.Cu" "*.Mask")
			(remove_unused_layers no)
			(net "LAN1_P4_P")
			(clearance 0.0508)
			(thermal_gap 0.0508)
		)
		(pad "8" thru_hole circle
			(at 8.89 -2.54 270)
			(size 1.3208 1.3208)
			(drill 0.9144)
			(layers "*.Cu" "*.Mask")
			(remove_unused_layers no)
			(net "LAN1_P4_N")
			(clearance 0.0508)
			(thermal_gap 0.0508)
		)
		(pad "9" thru_hole circle
			(at -1.854962 10.459974 270)
			(size 1.3208 1.3208)
			(drill 0.9144)
			(layers "*.Cu" "*.Mask")
			(remove_unused_layers no)
			(net "N42126764")
			(clearance 0.0508)
			(thermal_gap 0.0508)
		)
		(pad "10" thru_hole circle
			(at 0.635 10.459974 270)
			(size 1.3208 1.3208)
			(drill 0.9144)
			(layers "*.Cu" "*.Mask")
			(remove_unused_layers no)
			(net "N42126673")
			(clearance 0.0508)
			(thermal_gap 0.0508)
		)
		(pad "11" thru_hole circle
			(at 8.255 10.459974 270)
			(size 1.3208 1.3208)
			(drill 0.9144)
			(layers "*.Cu" "*.Mask")
			(remove_unused_layers no)
			(net "Net_446")
			(clearance 0.0508)
			(thermal_gap 0.0508)
		)
		(pad "12" thru_hole circle
			(at 10.744962 10.459974 270)
			(size 1.3208 1.3208)
			(drill 0.9144)
			(layers "*.Cu" "*.Mask")
			(remove_unused_layers no)
			(net "N42130542")
			(clearance 0.0508)
			(thermal_gap 0.0508)
		)
		(pad "G1" thru_hole circle
			(at -3.430016 2.500122 270)
			(size 2.3622 2.3622)
			(drill 1.6002)
			(layers "*.Cu" "*.Mask")
			(remove_unused_layers no)
			(net "GND")
			(clearance -0.127)
		)
		(pad "G2" thru_hole circle
			(at 12.320016 2.500122 270)
			(size 2.3622 2.3622)
			(drill 1.6002)
			(layers "*.Cu" "*.Mask")
			(remove_unused_layers no)
			(net "GND")
			(clearance -0.127)
		)
		(zone
			(layers "F.Cu" "B.Cu" "In1.Cu" "In2.Cu" "In3.Cu" "In4.Cu" "In5.Cu" "In6.Cu")
			(hatch none 0.5)
			(connect_pads
				(clearance 0)
			)
			(min_thickness 0.25)
			(keepout
				(tracks not_allowed)
				(vias allowed)
				(pads allowed)
				(copperpour not_allowed)
				(footprints allowed)
			)
			(placement
				(enabled no)
				(sheetname "")
			)
			(fill
				(thermal_gap 0.5)
				(thermal_bridge_width 0.5)
				(island_removal_mode 0)
			)
			(polygon
				(pts
					(arc
						(start 9.691116 -142.113)
						(mid 5.677916 -142.113)
						(end 9.691116 -142.113)
					)
				)
			)
		)
		(zone
			(layers "F.Cu" "B.Cu" "In1.Cu" "In2.Cu" "In3.Cu" "In4.Cu" "In5.Cu" "In6.Cu")
			(hatch none 0.5)
			(connect_pads
				(clearance 0)
			)
			(min_thickness 0.25)
			(keepout
				(tracks not_allowed)
				(vias allowed)
				(pads allowed)
				(copperpour not_allowed)
				(footprints allowed)
			)
			(placement
				(enabled no)
				(sheetname "")
			)
			(fill
				(thermal_gap 0.5)
				(thermal_bridge_width 0.5)
				(island_removal_mode 0)
			)
			(polygon
				(pts
					(arc
						(start 9.691116 -130.683)
						(mid 5.677916 -130.683)
						(end 9.691116 -130.683)
					)
				)
			)
		)
	)
	(footprint ""
		(layer "F.Cu")
		(at 50.217324 -173.13783 180)
		(property "Reference" "CE9"
			(at 0.06858 -5.780024 0)
			(unlocked yes)
			(layer "F.SilkS")
			(effects
				(font
					(size 0.7874 0.5842)
					(thickness 0.1524)
				)
				(justify left)
			)
		)
		(property "Value" ""
			(at 0 0 180)
			(layer "F.Fab")
			(effects
				(font
					(size 1.27 1.27)
				)
			)
		)
		(duplicate_pad_numbers_are_jumpers no)
		(fp_line
			(start 0 -4.2672)
			(end 0 4.2672)
			(stroke
				(width 0.1524)
				(type default)
			)
			(layer "F.SilkS")
		)
		(fp_circle
			(center 0 0)
			(end -4.2672 0)
			(stroke
				(width 0.1524)
				(type default)
			)
			(fill no)
			(layer "F.SilkS")
		)
		(fp_poly
			(pts
				(arc
					(start 0 -4.2672)
					(mid 4.2672 0)
					(end 0 4.2672)
				)
			)
			(stroke
				(width 0)
				(type default)
			)
			(fill yes)
			(layer "F.SilkS")
		)
		(fp_poly
			(pts
				(xy -2.5146 -0.762) (xy -0.9906 -0.762) (xy -0.9906 0.762) (xy -2.5146 0.762)
			)
			(stroke
				(width 0)
				(type default)
			)
			(fill no)
			(layer "B.CrtYd")
		)
		(fp_poly
			(pts
				(arc
					(start 1.7526 0.762)
					(mid 2.291415 -0.538815)
					(end 0.9906 0)
				)
				(arc
					(start 0.9906 0.0254)
					(mid 1.206345 0.546255)
					(end 1.7272 0.762)
				)
			)
			(stroke
				(width 0)
				(type default)
			)
			(fill no)
			(layer "B.CrtYd")
		)
		(fp_poly
			(pts
				(arc
					(start -4.2672 0)
					(mid 4.2672 0)
					(end -4.2672 0)
				)
			)
			(stroke
				(width 0)
				(type default)
			)
			(fill no)
			(layer "F.CrtYd")
		)
		(fp_circle
			(center 0 0)
			(end -4.2672 0)
			(stroke
				(width 0.1)
				(type default)
			)
			(fill no)
			(layer "F.Fab")
		)
		(fp_text user "+"
			(at -6.482842 0.822706 180)
			(unlocked yes)
			(layer "F.SilkS")
			(effects
				(font
					(size 1.905 1.4224)
					(thickness 0.1524)
				)
				(justify left)
			)
		)
		(fp_text user "+"
			(at -5.6642 -0.34925 180)
			(unlocked yes)
			(layer "F.Fab")
			(effects
				(font
					(size 1.905 1.4224)
					(thickness 0.000001)
				)
				(justify left)
			)
		)
		(pad "1" thru_hole rect
			(at -1.75006 0 180)
			(size 1.397 1.397)
			(drill 0.9144)
			(layers "*.Cu" "*.Mask")
			(remove_unused_layers no)
			(net "P12V")
			(clearance 0.0127)
			(thermal_gap 0.0127)
			(padstack
				(mode front_inner_back)
				(layer "Inner"
					(shape circle)
					(size 1.397 1.397)
					(clearance 0.0127)
				)
				(layer "B.Cu"
					(shape rect)
					(size 1.397 1.397)
					(clearance 0.0127)
				)
			)
		)
		(pad "2" thru_hole circle
			(at 1.75006 0 180)
			(size 1.397 1.397)
			(drill 0.9144)
			(layers "*.Cu" "*.Mask")
			(remove_unused_layers no)
			(net "GND")
			(clearance 0.0127)
			(thermal_gap 0.0127)
		)
	)
	(footprint ""
		(layer "F.Cu")
		(at 40.157654 -14.412976 180)
		(property "Reference" "R9"
			(at 0.747014 1.214628 0)
			(unlocked yes)
			(layer "F.SilkS")
			(effects
				(font
					(size 0.7874 0.5842)
					(thickness 0.1524)
				)
				(justify left)
			)
		)
		(property "Value" ""
			(at 0 0 180)
			(layer "F.Fab")
			(effects
				(font
					(size 1.27 1.27)
				)
			)
		)
		(duplicate_pad_numbers_are_jumpers no)
		(fp_line
			(start 0.7874 0.4064)
			(end -0.7874 0.4064)
			(stroke
				(width 0.1524)
				(type default)
			)
			(layer "F.SilkS")
		)
		(fp_line
			(start 0.7874 -0.4064)
			(end 0.7874 0.4064)
			(stroke
				(width 0.1524)
				(type default)
			)
			(layer "F.SilkS")
		)
		(fp_line
			(start -0.7874 0.4064)
			(end -0.7874 -0.4064)
			(stroke
				(width 0.1524)
				(type default)
			)
			(layer "F.SilkS")
		)
		(fp_line
			(start -0.7874 -0.4064)
			(end 0.7874 -0.4064)
			(stroke
				(width 0.1524)
				(type default)
			)
			(layer "F.SilkS")
		)
		(fp_poly
			(pts
				(xy -0.508 0.2794) (xy -0.508 0.2286) (xy -0.635 0.2286) (xy -0.635 -0.254) (xy -0.5334 -0.254)
				(xy -0.5334 -0.2794) (xy 0.5334 -0.2794) (xy 0.5334 -0.254) (xy 0.635 -0.254) (xy 0.635 0.254) (xy 0.5334 0.254)
				(xy 0.5334 0.2794)
			)
			(stroke
				(width 0)
				(type default)
			)
			(fill no)
			(layer "F.CrtYd")
		)
		(pad "1" smd rect
			(at 0.40005 0 180)
			(size 0.4572 0.508)
			(layers "F.Cu" "F.Mask" "F.Paste")
			(net "PSU1_RETURN")
		)
		(pad "2" smd rect
			(at -0.40005 0 180)
			(size 0.4572 0.508)
			(layers "F.Cu" "F.Mask" "F.Paste")
			(net "GND")
		)
	)
	(footprint ""
		(layer "F.Cu")
		(at 26.226008 -449.713858)
		(property "Reference" "R84"
			(at -2.92227 0.534924 0)
			(unlocked yes)
			(layer "F.SilkS")
			(effects
				(font
					(size 0.7874 0.5842)
					(thickness 0.1524)
				)
				(justify left)
			)
		)
		(property "Value" ""
			(at 0 0 0)
			(layer "F.Fab")
			(effects
				(font
					(size 1.27 1.27)
				)
			)
		)
		(duplicate_pad_numbers_are_jumpers no)
		(fp_line
			(start -0.7874 -0.4064)
			(end 0.7874 -0.4064)
			(stroke
				(width 0.1524)
				(type default)
			)
			(layer "F.SilkS")
		)
		(fp_line
			(start -0.7874 0.4064)
			(end -0.7874 -0.4064)
			(stroke
				(width 0.1524)
				(type default)
			)
			(layer "F.SilkS")
		)
		(fp_line
			(start 0.7874 -0.4064)
			(end 0.7874 0.4064)
			(stroke
				(width 0.1524)
				(type default)
			)
			(layer "F.SilkS")
		)
		(fp_line
			(start 0.7874 0.4064)
			(end -0.7874 0.4064)
			(stroke
				(width 0.1524)
				(type default)
			)
			(layer "F.SilkS")
		)
		(fp_poly
			(pts
				(xy -0.508 0.2794) (xy -0.508 0.2286) (xy -0.635 0.2286) (xy -0.635 -0.254) (xy -0.5334 -0.254)
				(xy -0.5334 -0.2794) (xy 0.5334 -0.2794) (xy 0.5334 -0.254) (xy 0.635 -0.254) (xy 0.635 0.254) (xy 0.5334 0.254)
				(xy 0.5334 0.2794)
			)
			(stroke
				(width 0)
				(type default)
			)
			(fill no)
			(layer "F.CrtYd")
		)
		(pad "1" smd rect
			(at 0.40005 0)
			(size 0.4572 0.508)
			(layers "F.Cu" "F.Mask" "F.Paste")
			(net "PSU6_RESET")
		)
		(pad "2" smd rect
			(at -0.40005 0)
			(size 0.4572 0.508)
			(layers "F.Cu" "F.Mask" "F.Paste")
			(net "P12V_STBY")
		)
	)
)
